FILE_TYPE=LIBRARY_PARTS;
primitive 'SN74LVC1G11DCKR';
  pin
    'A':
      PIN_NUMBER='(1)';
      INPUT_LOAD='(-0.01,0.01)';
    'B':
      PIN_NUMBER='(3)';
      INPUT_LOAD='(-0.01,0.01)';
    'C':
      PIN_NUMBER='(6)';
      INPUT_LOAD='(-0.01,0.01)';
    'VCC':
      PIN_NUMBER='(5)';
      PINUSE='POWER';
      NO_LOAD_CHECK='Both';
      NO_IO_CHECK='Both';
      NO_ASSERT_CHECK='TRUE';
      NO_DIR_CHECK='TRUE';
      ALLOW_CONNECT='TRUE';
    'Y':
      PIN_NUMBER='(4)';
      OUTPUT_LOAD='(1.0,-1.0)';
    'GND':
      PIN_NUMBER='(2)';
      PINUSE='POWER';
      NO_LOAD_CHECK='Both';
      NO_IO_CHECK='Both';
      NO_ASSERT_CHECK='TRUE';
      NO_DIR_CHECK='TRUE';
      ALLOW_CONNECT='TRUE';
  end_pin;
  body
    PART_NAME='SN74LVC1G11DCKR';
    BODY_NAME='SN74LVC1G11DCKR';
    PHYS_DES_PREFIX='U';
    CLASS='IC';
  end_body;
end_primitive;

END.
